# SCM (Grand Teton) — schematic netlist excerpt (pin names and nets, part order shuffled) for the footprints in the layout excerpt that follows; sources: Cadence DE-HDL packaged netlist, KiCad conversion of 12092022_DA0F0TMDCD0_F0T_Management_Board_D_brd_V3_OCP.brd

R217  Q_RES  0 5% CHIP  pkg 0402LF  page 15 : A = USB_HOST_BMC_A_R_DP ; B = USB_HOST_BMC_A_DP
PR530  Q_RES  12.4K 1% CHIP  pkg 0402LF  page 52 : A = GND ; B = P3V3_AUX_FB_RC

(kicad_pcb
	(version 20260206)
	(generator "pcbnew")
	(generator_version "10.0")
	(general
		(thickness 1.6)
		(legacy_teardrops no)
	)
	(paper "A4")
	(title_block
		(title "12092022_DA0F0TMDCD0_F0T_Management_Board_D_brd_V3_OCP.brd")
		(comment 1 "Grand Teton / footprints 332-333 of 1440")
	)
	(layers
		(0 "F.Cu" signal "TOP")
		(4 "In1.Cu" signal "GND")
		(6 "In2.Cu" signal "IN1")
		(8 "In3.Cu" signal "GND1")
		(10 "In4.Cu" signal "IN2")
		(12 "In5.Cu" signal "VCC")
		(14 "In6.Cu" signal "VCC1")
		(16 "In7.Cu" signal "IN3")
		(18 "In8.Cu" signal "GND2")
		(20 "In9.Cu" signal "IN4")
		(22 "In10.Cu" signal "GND3")
		(2 "B.Cu" signal "BOTTOM")
		(9 "F.Adhes" user "F.Adhesive")
		(11 "B.Adhes" user "B.Adhesive")
		(13 "F.Paste" user "Package Geometry/Pastemask Top")
		(15 "B.Paste" user "Package Geometry/Pastemask Bottom")
		(5 "F.SilkS" user "Ref Des/Silkscreen Top")
		(7 "B.SilkS" user "Ref Des/Silkscreen Bottom")
		(1 "F.Mask" user "Board Geometry/Soldermask Top")
		(3 "B.Mask" user "Board Geometry/Soldermask Bottom")
		(17 "Dwgs.User" user "User.Drawings")
		(19 "Cmts.User" user "User.Comments")
		(21 "Eco1.User" user "User.Eco1")
		(23 "Eco2.User" user "User.Eco2")
		(25 "Edge.Cuts" user "Board Geometry/Outline")
		(27 "Margin" user)
		(31 "F.CrtYd" user "Package Geometry/Place Bound Top")
		(29 "B.CrtYd" user "Package Geometry/Place Bound Bottom")
		(35 "F.Fab" user "Ref Des/Assembly Top")
		(33 "B.Fab" user "Ref Des/Assembly Bottom")
	)
	(footprint ""
		(layer "F.Cu")
		(at 11.27125 -64.54394 -90)
		(property "Reference" "PR530"
			(at 0 0 270)
			(layer "F.SilkS")
			(hide yes)
			(effects
				(font
					(size 1.27 1.27)
				)
			)
		)
		(property "Value" ""
			(at 0 0 270)
			(layer "F.Fab")
			(effects
				(font
					(size 1.27 1.27)
				)
			)
		)
		(duplicate_pad_numbers_are_jumpers no)
		(fp_line
			(start -0.7874 0.4064)
			(end -0.7874 -0.4064)
			(stroke
				(width 0.1524)
				(type default)
			)
			(layer "F.SilkS")
		)
		(fp_line
			(start 0.7874 0.4064)
			(end -0.7874 0.4064)
			(stroke
				(width 0.1524)
				(type default)
			)
			(layer "F.SilkS")
		)
		(fp_line
			(start -0.7874 -0.4064)
			(end 0.7874 -0.4064)
			(stroke
				(width 0.1524)
				(type default)
			)
			(layer "F.SilkS")
		)
		(fp_line
			(start 0.7874 -0.4064)
			(end 0.7874 0.4064)
			(stroke
				(width 0.1524)
				(type default)
			)
			(layer "F.SilkS")
		)
		(fp_line
			(start -0.67945 0.3048)
			(end -0.67945 -0.305054)
			(stroke
				(width 0.1)
				(type default)
			)
			(layer "F.Fab")
		)
		(fp_line
			(start -0.12065 0.3048)
			(end -0.67945 0.3048)
			(stroke
				(width 0.1)
				(type default)
			)
			(layer "F.Fab")
		)
		(fp_line
			(start 0.120396 0.3048)
			(end 0.120396 0.2794)
			(stroke
				(width 0.1)
				(type default)
			)
			(layer "F.Fab")
		)
		(fp_line
			(start 0.67945 0.3048)
			(end 0.120396 0.3048)
			(stroke
				(width 0.1)
				(type default)
			)
			(layer "F.Fab")
		)
		(fp_line
			(start -0.12065 0.2794)
			(end -0.12065 0.3048)
			(stroke
				(width 0.1)
				(type default)
			)
			(layer "F.Fab")
		)
		(fp_line
			(start 0.120396 0.2794)
			(end -0.12065 0.2794)
			(stroke
				(width 0.1)
				(type default)
			)
			(layer "F.Fab")
		)
		(fp_line
			(start -0.12065 -0.2794)
			(end 0.12065 -0.2794)
			(stroke
				(width 0.1)
				(type default)
			)
			(layer "F.Fab")
		)
		(fp_line
			(start 0.12065 -0.2794)
			(end 0.12065 -0.3048)
			(stroke
				(width 0.1)
				(type default)
			)
			(layer "F.Fab")
		)
		(fp_line
			(start 0.12065 -0.3048)
			(end 0.67945 -0.3048)
			(stroke
				(width 0.1)
				(type default)
			)
			(layer "F.Fab")
		)
		(fp_line
			(start 0.67945 -0.3048)
			(end 0.67945 0.3048)
			(stroke
				(width 0.1)
				(type default)
			)
			(layer "F.Fab")
		)
		(fp_line
			(start -0.67945 -0.305054)
			(end -0.12065 -0.305054)
			(stroke
				(width 0.1)
				(type default)
			)
			(layer "F.Fab")
		)
		(fp_line
			(start -0.12065 -0.305054)
			(end -0.12065 -0.2794)
			(stroke
				(width 0.1)
				(type default)
			)
			(layer "F.Fab")
		)
		(pad "1" smd circle
			(at -0.40005 0 270)
			(size 0 0)
			(layers "F.Cu" "F.Mask" "F.Paste")
			(net "GND")
		)
		(pad "2" smd circle
			(at 0.40005 0 270)
			(size 0 0)
			(layers "F.Cu" "F.Mask" "F.Paste")
			(net "P3V3_AUX_FB_RC")
		)
	)
	(footprint ""
		(layer "F.Cu")
		(at 64.600328 -29.377132 -90)
		(property "Reference" "R217"
			(at 0 0 270)
			(layer "F.SilkS")
			(hide yes)
			(effects
				(font
					(size 1.27 1.27)
				)
			)
		)
		(property "Value" ""
			(at 0 0 270)
			(layer "F.Fab")
			(effects
				(font
					(size 1.27 1.27)
				)
			)
		)
		(duplicate_pad_numbers_are_jumpers no)
		(fp_line
			(start -0.7874 0.4064)
			(end -0.7874 -0.167132)
			(stroke
				(width 0.1524)
				(type default)
			)
			(layer "F.SilkS")
		)
		(fp_line
			(start 0.7874 0.4064)
			(end -0.7874 0.4064)
			(stroke
				(width 0.1524)
				(type default)
			)
			(layer "F.SilkS")
		)
		(fp_line
			(start 0.7874 -0.062992)
			(end 0.7874 0.4064)
			(stroke
				(width 0.1524)
				(type default)
			)
			(layer "F.SilkS")
		)
		(fp_line
			(start -0.397002 -0.4064)
			(end 0.277368 -0.4064)
			(stroke
				(width 0.1524)
				(type default)
			)
			(layer "F.SilkS")
		)
		(fp_line
			(start -0.67945 0.3048)
			(end -0.67945 -0.305054)
			(stroke
				(width 0.1)
				(type default)
			)
			(layer "F.Fab")
		)
		(fp_line
			(start -0.12065 0.3048)
			(end -0.67945 0.3048)
			(stroke
				(width 0.1)
				(type default)
			)
			(layer "F.Fab")
		)
		(fp_line
			(start 0.120396 0.3048)
			(end 0.120396 0.2794)
			(stroke
				(width 0.1)
				(type default)
			)
			(layer "F.Fab")
		)
		(fp_line
			(start 0.67945 0.3048)
			(end 0.120396 0.3048)
			(stroke
				(width 0.1)
				(type default)
			)
			(layer "F.Fab")
		)
		(fp_line
			(start -0.12065 0.2794)
			(end -0.12065 0.3048)
			(stroke
				(width 0.1)
				(type default)
			)
			(layer "F.Fab")
		)
		(fp_line
			(start 0.120396 0.2794)
			(end -0.12065 0.2794)
			(stroke
				(width 0.1)
				(type default)
			)
			(layer "F.Fab")
		)
		(fp_line
			(start -0.12065 -0.2794)
			(end 0.12065 -0.2794)
			(stroke
				(width 0.1)
				(type default)
			)
			(layer "F.Fab")
		)
		(fp_line
			(start 0.12065 -0.2794)
			(end 0.12065 -0.3048)
			(stroke
				(width 0.1)
				(type default)
			)
			(layer "F.Fab")
		)
		(fp_line
			(start 0.12065 -0.3048)
			(end 0.67945 -0.3048)
			(stroke
				(width 0.1)
				(type default)
			)
			(layer "F.Fab")
		)
		(fp_line
			(start 0.67945 -0.3048)
			(end 0.67945 0.3048)
			(stroke
				(width 0.1)
				(type default)
			)
			(layer "F.Fab")
		)
		(fp_line
			(start -0.67945 -0.305054)
			(end -0.12065 -0.305054)
			(stroke
				(width 0.1)
				(type default)
			)
			(layer "F.Fab")
		)
		(fp_line
			(start -0.12065 -0.305054)
			(end -0.12065 -0.2794)
			(stroke
				(width 0.1)
				(type default)
			)
			(layer "F.Fab")
		)
		(pad "1" smd circle
			(at -0.40005 0 270)
			(size 0 0)
			(layers "F.Cu" "F.Mask" "F.Paste")
			(net "USB_HOST_BMC_A_R_DP")
		)
		(pad "2" smd circle
			(at 0.40005 0 270)
			(size 0 0)
			(layers "F.Cu" "F.Mask" "F.Paste")
			(net "USB_HOST_BMC_A_DP")
		)
	)
)
